(kicad_pcb
	(version 20260206)
	(generator "pcbnew")
	(generator_version "10.0")
	(general
		(thickness 1.6)
		(legacy_teardrops no)
	)
	(paper "A4")
	(title_block
		(title "01162023_DA0F0TEBIF0_F0T_Expander_BD_F_brd_V02_OCP.brd")
		(comment 1 "Grand Teton / footprints 4056-4062 of 9728")
	)
	(layers
		(0 "F.Cu" signal "TOP")
		(4 "In1.Cu" signal "GND")
		(6 "In2.Cu" signal "VCC")
		(8 "In3.Cu" signal "VCC1")
		(10 "In4.Cu" signal "GND1")
		(12 "In5.Cu" signal "IN1")
		(14 "In6.Cu" signal "GND2")
		(16 "In7.Cu" signal "IN2")
		(18 "In8.Cu" signal "GND3")
		(20 "In9.Cu" signal "IN3")
		(22 "In10.Cu" signal "GND4")
		(24 "In11.Cu" signal "IN4")
		(26 "In12.Cu" signal "GND5")
		(28 "In13.Cu" signal "IN5")
		(30 "In14.Cu" signal "GND6")
		(32 "In15.Cu" signal "IN6")
		(34 "In16.Cu" signal "GND7")
		(2 "B.Cu" signal "BOTTOM")
		(9 "F.Adhes" user "F.Adhesive")
		(11 "B.Adhes" user "B.Adhesive")
		(13 "F.Paste" user "Package Geometry/Pastemask Top")
		(15 "B.Paste" user "Package Geometry/Pastemask Bottom")
		(5 "F.SilkS" user "Ref Des/Silkscreen Top")
		(7 "B.SilkS" user "Ref Des/Silkscreen Bottom")
		(1 "F.Mask" user "Board Geometry/Soldermask Top")
		(3 "B.Mask" user "Board Geometry/Soldermask Bottom")
		(17 "Dwgs.User" user "User.Drawings")
		(19 "Cmts.User" user "User.Comments")
		(21 "Eco1.User" user "User.Eco1")
		(23 "Eco2.User" user "User.Eco2")
		(25 "Edge.Cuts" user "Board Geometry/Outline")
		(27 "Margin" user)
		(31 "F.CrtYd" user "Package Geometry/Place Bound Top")
		(29 "B.CrtYd" user "Package Geometry/Place Bound Bottom")
		(35 "F.Fab" user "Ref Des/Assembly Top")
		(33 "B.Fab" user "Ref Des/Assembly Bottom")
	)
	(footprint ""
		(layer "F.Cu")
		(at 460.611982 -107.848654 180)
		(property "Reference" "R961"
			(at 0 0 180)
			(layer "F.SilkS")
			(hide yes)
			(effects
				(font
					(size 1.27 1.27)
				)
			)
		)
		(property "Value" ""
			(at 0 0 180)
			(layer "F.Fab")
			(effects
				(font
					(size 1.27 1.27)
				)
			)
		)
		(duplicate_pad_numbers_are_jumpers no)
		(fp_line
			(start 0.7874 0.4064)
			(end -0.7874 0.4064)
			(stroke
				(width 0.1524)
				(type default)
			)
			(layer "F.SilkS")
		)
		(fp_line
			(start 0.7874 -0.4064)
			(end 0.7874 0.4064)
			(stroke
				(width 0.1524)
				(type default)
			)
			(layer "F.SilkS")
		)
		(fp_line
			(start -0.7874 0.4064)
			(end -0.7874 -0.4064)
			(stroke
				(width 0.1524)
				(type default)
			)
			(layer "F.SilkS")
		)
		(fp_line
			(start -0.7874 -0.4064)
			(end 0.7874 -0.4064)
			(stroke
				(width 0.1524)
				(type default)
			)
			(layer "F.SilkS")
		)
		(fp_line
			(start 0.67945 0.3048)
			(end 0.120396 0.3048)
			(stroke
				(width 0.1)
				(type default)
			)
			(layer "F.Fab")
		)
		(fp_line
			(start 0.67945 -0.3048)
			(end 0.67945 0.3048)
			(stroke
				(width 0.1)
				(type default)
			)
			(layer "F.Fab")
		)
		(fp_line
			(start 0.12065 -0.2794)
			(end 0.12065 -0.3048)
			(stroke
				(width 0.1)
				(type default)
			)
			(layer "F.Fab")
		)
		(fp_line
			(start 0.12065 -0.3048)
			(end 0.67945 -0.3048)
			(stroke
				(width 0.1)
				(type default)
			)
			(layer "F.Fab")
		)
		(fp_line
			(start 0.120396 0.3048)
			(end 0.120396 0.2794)
			(stroke
				(width 0.1)
				(type default)
			)
			(layer "F.Fab")
		)
		(fp_line
			(start 0.120396 0.2794)
			(end -0.12065 0.2794)
			(stroke
				(width 0.1)
				(type default)
			)
			(layer "F.Fab")
		)
		(fp_line
			(start -0.12065 0.3048)
			(end -0.67945 0.3048)
			(stroke
				(width 0.1)
				(type default)
			)
			(layer "F.Fab")
		)
		(fp_line
			(start -0.12065 0.2794)
			(end -0.12065 0.3048)
			(stroke
				(width 0.1)
				(type default)
			)
			(layer "F.Fab")
		)
		(fp_line
			(start -0.12065 -0.2794)
			(end 0.12065 -0.2794)
			(stroke
				(width 0.1)
				(type default)
			)
			(layer "F.Fab")
		)
		(fp_line
			(start -0.12065 -0.305054)
			(end -0.12065 -0.2794)
			(stroke
				(width 0.1)
				(type default)
			)
			(layer "F.Fab")
		)
		(fp_line
			(start -0.67945 0.3048)
			(end -0.67945 -0.305054)
			(stroke
				(width 0.1)
				(type default)
			)
			(layer "F.Fab")
		)
		(fp_line
			(start -0.67945 -0.305054)
			(end -0.12065 -0.305054)
			(stroke
				(width 0.1)
				(type default)
			)
			(layer "F.Fab")
		)
		(pad "1" smd circle
			(at -0.40005 0 180)
			(size 0 0)
			(layers "F.Cu" "F.Mask" "F.Paste")
			(net "HP_NIC7_EN")
		)
		(pad "2" smd circle
			(at 0.40005 0 180)
			(size 0 0)
			(layers "F.Cu" "F.Mask" "F.Paste")
			(net "P12V_NIC7_CO_EN")
		)
	)
	(footprint ""
		(layer "F.Cu")
		(at 90.039444 -96.811592 -90)
		(property "Reference" "R697"
			(at 0 0 270)
			(layer "F.SilkS")
			(hide yes)
			(effects
				(font
					(size 1.27 1.27)
				)
			)
		)
		(property "Value" ""
			(at 0 0 270)
			(layer "F.Fab")
			(effects
				(font
					(size 1.27 1.27)
				)
			)
		)
		(duplicate_pad_numbers_are_jumpers no)
		(fp_line
			(start -0.7874 0.4064)
			(end -0.7874 -0.4064)
			(stroke
				(width 0.1524)
				(type default)
			)
			(layer "F.SilkS")
		)
		(fp_line
			(start 0.7874 0.4064)
			(end -0.7874 0.4064)
			(stroke
				(width 0.1524)
				(type default)
			)
			(layer "F.SilkS")
		)
		(fp_line
			(start -0.7874 -0.4064)
			(end 0.7874 -0.4064)
			(stroke
				(width 0.1524)
				(type default)
			)
			(layer "F.SilkS")
		)
		(fp_line
			(start 0.7874 -0.4064)
			(end 0.7874 0.4064)
			(stroke
				(width 0.1524)
				(type default)
			)
			(layer "F.SilkS")
		)
		(fp_line
			(start -0.67945 0.3048)
			(end -0.67945 -0.305054)
			(stroke
				(width 0.1)
				(type default)
			)
			(layer "F.Fab")
		)
		(fp_line
			(start -0.12065 0.3048)
			(end -0.67945 0.3048)
			(stroke
				(width 0.1)
				(type default)
			)
			(layer "F.Fab")
		)
		(fp_line
			(start 0.120396 0.3048)
			(end 0.120396 0.2794)
			(stroke
				(width 0.1)
				(type default)
			)
			(layer "F.Fab")
		)
		(fp_line
			(start 0.67945 0.3048)
			(end 0.120396 0.3048)
			(stroke
				(width 0.1)
				(type default)
			)
			(layer "F.Fab")
		)
		(fp_line
			(start -0.12065 0.2794)
			(end -0.12065 0.3048)
			(stroke
				(width 0.1)
				(type default)
			)
			(layer "F.Fab")
		)
		(fp_line
			(start 0.120396 0.2794)
			(end -0.12065 0.2794)
			(stroke
				(width 0.1)
				(type default)
			)
			(layer "F.Fab")
		)
		(fp_line
			(start -0.12065 -0.2794)
			(end 0.12065 -0.2794)
			(stroke
				(width 0.1)
				(type default)
			)
			(layer "F.Fab")
		)
		(fp_line
			(start 0.12065 -0.2794)
			(end 0.12065 -0.3048)
			(stroke
				(width 0.1)
				(type default)
			)
			(layer "F.Fab")
		)
		(fp_line
			(start 0.12065 -0.3048)
			(end 0.67945 -0.3048)
			(stroke
				(width 0.1)
				(type default)
			)
			(layer "F.Fab")
		)
		(fp_line
			(start 0.67945 -0.3048)
			(end 0.67945 0.3048)
			(stroke
				(width 0.1)
				(type default)
			)
			(layer "F.Fab")
		)
		(fp_line
			(start -0.67945 -0.305054)
			(end -0.12065 -0.305054)
			(stroke
				(width 0.1)
				(type default)
			)
			(layer "F.Fab")
		)
		(fp_line
			(start -0.12065 -0.305054)
			(end -0.12065 -0.2794)
			(stroke
				(width 0.1)
				(type default)
			)
			(layer "F.Fab")
		)
		(pad "1" smd circle
			(at -0.40005 0 270)
			(size 0 0)
			(layers "F.Cu" "F.Mask" "F.Paste")
			(net "NIC1_ADC_A0")
		)
		(pad "2" smd circle
			(at 0.40005 0 270)
			(size 0 0)
			(layers "F.Cu" "F.Mask" "F.Paste")
			(net "GND")
		)
	)
	(footprint ""
		(layer "F.Cu")
		(at 473.594938 -554.99508 90)
		(property "Reference" "HS_BP1"
			(at -0.5842 -1.31953 90)
			(unlocked yes)
			(layer "B.SilkS")
			(effects
				(font
					(size 0.7874 0.5842)
					(thickness 0.1524)
				)
				(justify left mirror)
			)
		)
		(property "Value" ""
			(at 0 0 90)
			(layer "F.Fab")
			(effects
				(font
					(size 1.27 1.27)
				)
			)
		)
		(duplicate_pad_numbers_are_jumpers no)
		(pad "1" thru_hole circle
			(at 0 0 90)
			(size 0.4572 0.4572)
			(drill 0.2032)
			(layers "*.Cu" "*.Mask")
			(remove_unused_layers no)
			(net "Net_9201")
			(clearance 0.127)
			(thermal_gap 0.127)
			(padstack
				(mode front_inner_back)
				(layer "Inner"
					(shape circle)
					(size 0.4572 0.4572)
					(clearance 0.127)
				)
				(layer "B.Cu"
					(shape circle)
					(size 0.508 0.508)
					(clearance 0.1016)
				)
			)
		)
	)
	(footprint ""
		(layer "F.Cu")
		(at 99.469956 -237.401354 90)
		(property "Reference" "PC290"
			(at 0 0 90)
			(layer "F.SilkS")
			(hide yes)
			(effects
				(font
					(size 1.27 1.27)
				)
			)
		)
		(property "Value" ""
			(at 0 0 90)
			(layer "F.Fab")
			(effects
				(font
					(size 1.27 1.27)
				)
			)
		)
		(duplicate_pad_numbers_are_jumpers no)
		(fp_line
			(start 0.7874 -0.4064)
			(end 0.7874 0.4064)
			(stroke
				(width 0.1524)
				(type default)
			)
			(layer "F.SilkS")
		)
		(fp_line
			(start -0.7874 -0.4064)
			(end 0.7874 -0.4064)
			(stroke
				(width 0.1524)
				(type default)
			)
			(layer "F.SilkS")
		)
		(fp_line
			(start 0.7874 0.4064)
			(end -0.7874 0.4064)
			(stroke
				(width 0.1524)
				(type default)
			)
			(layer "F.SilkS")
		)
		(fp_line
			(start -0.7874 0.4064)
			(end -0.7874 -0.4064)
			(stroke
				(width 0.1524)
				(type default)
			)
			(layer "F.SilkS")
		)
		(fp_line
			(start -0.12065 -0.305054)
			(end -0.12065 -0.2794)
			(stroke
				(width 0.1)
				(type default)
			)
			(layer "F.Fab")
		)
		(fp_line
			(start -0.67945 -0.305054)
			(end -0.12065 -0.305054)
			(stroke
				(width 0.1)
				(type default)
			)
			(layer "F.Fab")
		)
		(fp_line
			(start 0.67945 -0.3048)
			(end 0.67945 0.3048)
			(stroke
				(width 0.1)
				(type default)
			)
			(layer "F.Fab")
		)
		(fp_line
			(start 0.12065 -0.3048)
			(end 0.67945 -0.3048)
			(stroke
				(width 0.1)
				(type default)
			)
			(layer "F.Fab")
		)
		(fp_line
			(start 0.12065 -0.2794)
			(end 0.12065 -0.3048)
			(stroke
				(width 0.1)
				(type default)
			)
			(layer "F.Fab")
		)
		(fp_line
			(start -0.12065 -0.2794)
			(end 0.12065 -0.2794)
			(stroke
				(width 0.1)
				(type default)
			)
			(layer "F.Fab")
		)
		(fp_line
			(start 0.120396 0.2794)
			(end -0.12065 0.2794)
			(stroke
				(width 0.1)
				(type default)
			)
			(layer "F.Fab")
		)
		(fp_line
			(start -0.12065 0.2794)
			(end -0.12065 0.3048)
			(stroke
				(width 0.1)
				(type default)
			)
			(layer "F.Fab")
		)
		(fp_line
			(start 0.67945 0.3048)
			(end 0.120396 0.3048)
			(stroke
				(width 0.1)
				(type default)
			)
			(layer "F.Fab")
		)
		(fp_line
			(start 0.120396 0.3048)
			(end 0.120396 0.2794)
			(stroke
				(width 0.1)
				(type default)
			)
			(layer "F.Fab")
		)
		(fp_line
			(start -0.12065 0.3048)
			(end -0.67945 0.3048)
			(stroke
				(width 0.1)
				(type default)
			)
			(layer "F.Fab")
		)
		(fp_line
			(start -0.67945 0.3048)
			(end -0.67945 -0.305054)
			(stroke
				(width 0.1)
				(type default)
			)
			(layer "F.Fab")
		)
		(pad "1" smd circle
			(at -0.40005 0 90)
			(size 0 0)
			(layers "F.Cu" "F.Mask" "F.Paste")
			(net "P1V8_PEX_R")
		)
		(pad "2" smd circle
			(at 0.40005 0 90)
			(size 0 0)
			(layers "F.Cu" "F.Mask" "F.Paste")
			(net "GND")
		)
	)
	(footprint ""
		(layer "F.Cu")
		(at 129.545588 -114.385852 -90)
		(property "Reference" "PC788"
			(at 0 0 270)
			(layer "F.SilkS")
			(hide yes)
			(effects
				(font
					(size 1.27 1.27)
				)
			)
		)
		(property "Value" ""
			(at 0 0 270)
			(layer "F.Fab")
			(effects
				(font
					(size 1.27 1.27)
				)
			)
		)
		(duplicate_pad_numbers_are_jumpers no)
		(fp_line
			(start -0.7874 0.4064)
			(end -0.7874 -0.4064)
			(stroke
				(width 0.1524)
				(type default)
			)
			(layer "F.SilkS")
		)
		(fp_line
			(start 0.7874 0.4064)
			(end -0.7874 0.4064)
			(stroke
				(width 0.1524)
				(type default)
			)
			(layer "F.SilkS")
		)
		(fp_line
			(start -0.7874 -0.4064)
			(end 0.7874 -0.4064)
			(stroke
				(width 0.1524)
				(type default)
			)
			(layer "F.SilkS")
		)
		(fp_line
			(start 0.7874 -0.4064)
			(end 0.7874 0.4064)
			(stroke
				(width 0.1524)
				(type default)
			)
			(layer "F.SilkS")
		)
		(fp_line
			(start -0.67945 0.3048)
			(end -0.67945 -0.305054)
			(stroke
				(width 0.1)
				(type default)
			)
			(layer "F.Fab")
		)
		(fp_line
			(start -0.12065 0.3048)
			(end -0.67945 0.3048)
			(stroke
				(width 0.1)
				(type default)
			)
			(layer "F.Fab")
		)
		(fp_line
			(start 0.120396 0.3048)
			(end 0.120396 0.2794)
			(stroke
				(width 0.1)
				(type default)
			)
			(layer "F.Fab")
		)
		(fp_line
			(start 0.67945 0.3048)
			(end 0.120396 0.3048)
			(stroke
				(width 0.1)
				(type default)
			)
			(layer "F.Fab")
		)
		(fp_line
			(start -0.12065 0.2794)
			(end -0.12065 0.3048)
			(stroke
				(width 0.1)
				(type default)
			)
			(layer "F.Fab")
		)
		(fp_line
			(start 0.120396 0.2794)
			(end -0.12065 0.2794)
			(stroke
				(width 0.1)
				(type default)
			)
			(layer "F.Fab")
		)
		(fp_line
			(start -0.12065 -0.2794)
			(end 0.12065 -0.2794)
			(stroke
				(width 0.1)
				(type default)
			)
			(layer "F.Fab")
		)
		(fp_line
			(start 0.12065 -0.2794)
			(end 0.12065 -0.3048)
			(stroke
				(width 0.1)
				(type default)
			)
			(layer "F.Fab")
		)
		(fp_line
			(start 0.12065 -0.3048)
			(end 0.67945 -0.3048)
			(stroke
				(width 0.1)
				(type default)
			)
			(layer "F.Fab")
		)
		(fp_line
			(start 0.67945 -0.3048)
			(end 0.67945 0.3048)
			(stroke
				(width 0.1)
				(type default)
			)
			(layer "F.Fab")
		)
		(fp_line
			(start -0.67945 -0.305054)
			(end -0.12065 -0.305054)
			(stroke
				(width 0.1)
				(type default)
			)
			(layer "F.Fab")
		)
		(fp_line
			(start -0.12065 -0.305054)
			(end -0.12065 -0.2794)
			(stroke
				(width 0.1)
				(type default)
			)
			(layer "F.Fab")
		)
		(pad "1" smd circle
			(at -0.40005 0 270)
			(size 0 0)
			(layers "F.Cu" "F.Mask" "F.Paste")
			(net "P3V3_AUX")
		)
		(pad "2" smd circle
			(at 0.40005 0 270)
			(size 0 0)
			(layers "F.Cu" "F.Mask" "F.Paste")
			(net "GND")
		)
	)
	(footprint ""
		(layer "F.Cu")
		(at 452.543672 -42.84091)
		(property "Reference" "R671"
			(at 0 0 0)
			(layer "F.SilkS")
			(hide yes)
			(effects
				(font
					(size 1.27 1.27)
				)
			)
		)
		(property "Value" ""
			(at 0 0 0)
			(layer "F.Fab")
			(effects
				(font
					(size 1.27 1.27)
				)
			)
		)
		(duplicate_pad_numbers_are_jumpers no)
		(fp_line
			(start -0.7874 -0.4064)
			(end 0.7874 -0.4064)
			(stroke
				(width 0.1524)
				(type default)
			)
			(layer "F.SilkS")
		)
		(fp_line
			(start -0.7874 0.4064)
			(end -0.7874 -0.4064)
			(stroke
				(width 0.1524)
				(type default)
			)
			(layer "F.SilkS")
		)
		(fp_line
			(start 0.7874 -0.4064)
			(end 0.7874 0.4064)
			(stroke
				(width 0.1524)
				(type default)
			)
			(layer "F.SilkS")
		)
		(fp_line
			(start 0.7874 0.4064)
			(end -0.7874 0.4064)
			(stroke
				(width 0.1524)
				(type default)
			)
			(layer "F.SilkS")
		)
		(fp_line
			(start -0.67945 -0.305054)
			(end -0.12065 -0.305054)
			(stroke
				(width 0.1)
				(type default)
			)
			(layer "F.Fab")
		)
		(fp_line
			(start -0.67945 0.3048)
			(end -0.67945 -0.305054)
			(stroke
				(width 0.1)
				(type default)
			)
			(layer "F.Fab")
		)
		(fp_line
			(start -0.12065 -0.305054)
			(end -0.12065 -0.2794)
			(stroke
				(width 0.1)
				(type default)
			)
			(layer "F.Fab")
		)
		(fp_line
			(start -0.12065 -0.2794)
			(end 0.12065 -0.2794)
			(stroke
				(width 0.1)
				(type default)
			)
			(layer "F.Fab")
		)
		(fp_line
			(start -0.12065 0.2794)
			(end -0.12065 0.3048)
			(stroke
				(width 0.1)
				(type default)
			)
			(layer "F.Fab")
		)
		(fp_line
			(start -0.12065 0.3048)
			(end -0.67945 0.3048)
			(stroke
				(width 0.1)
				(type default)
			)
			(layer "F.Fab")
		)
		(fp_line
			(start 0.120396 0.2794)
			(end -0.12065 0.2794)
			(stroke
				(width 0.1)
				(type default)
			)
			(layer "F.Fab")
		)
		(fp_line
			(start 0.120396 0.3048)
			(end 0.120396 0.2794)
			(stroke
				(width 0.1)
				(type default)
			)
			(layer "F.Fab")
		)
		(fp_line
			(start 0.12065 -0.3048)
			(end 0.67945 -0.3048)
			(stroke
				(width 0.1)
				(type default)
			)
			(layer "F.Fab")
		)
		(fp_line
			(start 0.12065 -0.2794)
			(end 0.12065 -0.3048)
			(stroke
				(width 0.1)
				(type default)
			)
			(layer "F.Fab")
		)
		(fp_line
			(start 0.67945 -0.3048)
			(end 0.67945 0.3048)
			(stroke
				(width 0.1)
				(type default)
			)
			(layer "F.Fab")
		)
		(fp_line
			(start 0.67945 0.3048)
			(end 0.120396 0.3048)
			(stroke
				(width 0.1)
				(type default)
			)
			(layer "F.Fab")
		)
		(pad "1" smd circle
			(at -0.40005 0)
			(size 0 0)
			(layers "F.Cu" "F.Mask" "F.Paste")
			(net "SSD15_ADC_A1")
		)
		(pad "2" smd circle
			(at 0.40005 0)
			(size 0 0)
			(layers "F.Cu" "F.Mask" "F.Paste")
			(net "P3V3_AUX")
		)
	)
	(footprint ""
		(layer "F.Cu")
		(at 217.902536 -257.975862 -90)
		(property "Reference" "R6503"
			(at 0 0 270)
			(layer "F.SilkS")
			(hide yes)
			(effects
				(font
					(size 1.27 1.27)
				)
			)
		)
		(property "Value" ""
			(at 0 0 270)
			(layer "F.Fab")
			(effects
				(font
					(size 1.27 1.27)
				)
			)
		)
		(duplicate_pad_numbers_are_jumpers no)
		(fp_line
			(start -0.7874 0.4064)
			(end -0.7874 -0.4064)
			(stroke
				(width 0.1524)
				(type default)
			)
			(layer "F.SilkS")
		)
		(fp_line
			(start 0.7874 0.4064)
			(end -0.7874 0.4064)
			(stroke
				(width 0.1524)
				(type default)
			)
			(layer "F.SilkS")
		)
		(fp_line
			(start -0.7874 -0.4064)
			(end 0.7874 -0.4064)
			(stroke
				(width 0.1524)
				(type default)
			)
			(layer "F.SilkS")
		)
		(fp_line
			(start 0.7874 -0.4064)
			(end 0.7874 0.4064)
			(stroke
				(width 0.1524)
				(type default)
			)
			(layer "F.SilkS")
		)
		(fp_line
			(start -0.67945 0.3048)
			(end -0.67945 -0.305054)
			(stroke
				(width 0.1)
				(type default)
			)
			(layer "F.Fab")
		)
		(fp_line
			(start -0.12065 0.3048)
			(end -0.67945 0.3048)
			(stroke
				(width 0.1)
				(type default)
			)
			(layer "F.Fab")
		)
		(fp_line
			(start 0.120396 0.3048)
			(end 0.120396 0.2794)
			(stroke
				(width 0.1)
				(type default)
			)
			(layer "F.Fab")
		)
		(fp_line
			(start 0.67945 0.3048)
			(end 0.120396 0.3048)
			(stroke
				(width 0.1)
				(type default)
			)
			(layer "F.Fab")
		)
		(fp_line
			(start -0.12065 0.2794)
			(end -0.12065 0.3048)
			(stroke
				(width 0.1)
				(type default)
			)
			(layer "F.Fab")
		)
		(fp_line
			(start 0.120396 0.2794)
			(end -0.12065 0.2794)
			(stroke
				(width 0.1)
				(type default)
			)
			(layer "F.Fab")
		)
		(fp_line
			(start -0.12065 -0.2794)
			(end 0.12065 -0.2794)
			(stroke
				(width 0.1)
				(type default)
			)
			(layer "F.Fab")
		)
		(fp_line
			(start 0.12065 -0.2794)
			(end 0.12065 -0.3048)
			(stroke
				(width 0.1)
				(type default)
			)
			(layer "F.Fab")
		)
		(fp_line
			(start 0.12065 -0.3048)
			(end 0.67945 -0.3048)
			(stroke
				(width 0.1)
				(type default)
			)
			(layer "F.Fab")
		)
		(fp_line
			(start 0.67945 -0.3048)
			(end 0.67945 0.3048)
			(stroke
				(width 0.1)
				(type default)
			)
			(layer "F.Fab")
		)
		(fp_line
			(start -0.67945 -0.305054)
			(end -0.12065 -0.305054)
			(stroke
				(width 0.1)
				(type default)
			)
			(layer "F.Fab")
		)
		(fp_line
			(start -0.12065 -0.305054)
			(end -0.12065 -0.2794)
			(stroke
				(width 0.1)
				(type default)
			)
			(layer "F.Fab")
		)
		(pad "1" smd circle
			(at -0.40005 0 270)
			(size 0 0)
			(layers "F.Cu" "F.Mask" "F.Paste")
			(net "P1V25_SERDES_VDDPLL_PEX1")
		)
		(pad "2" smd circle
			(at 0.40005 0 270)
			(size 0 0)
			(layers "F.Cu" "F.Mask" "F.Paste")
			(net "P1V25_SERDES_VDDPLL_PEX1_C10")
		)
	)
)
